(kicad_pcb
	(version 20241229)
	(generator "pcbnew")
	(generator_version "9.0")
	(general
		(thickness 1.6642)
		(legacy_teardrops no)
	)
	(paper "A3")
	(title_block
		(title "PolarFire SoM")
		(date "2025-07-22")
		(rev "1.1.4")
		(company "Antmicro Ltd")
		(comment 1 "www.antmicro.com")
		(comment 9 "footprints 451-455 of 470")
	)
	(layers
		(0 "F.Cu" mixed)
		(4 "In1.Cu" power)
		(6 "In2.Cu" signal)
		(8 "In3.Cu" power)
		(10 "In4.Cu" signal)
		(12 "In5.Cu" power)
		(14 "In6.Cu" power)
		(16 "In7.Cu" signal)
		(18 "In8.Cu" power)
		(20 "In9.Cu" signal)
		(22 "In10.Cu" power)
		(24 "In11.Cu" signal)
		(26 "In12.Cu" signal)
		(2 "B.Cu" mixed)
		(9 "F.Adhes" user "F.Adhesive")
		(11 "B.Adhes" user "B.Adhesive")
		(13 "F.Paste" user)
		(15 "B.Paste" user)
		(5 "F.SilkS" user "F.Silkscreen")
		(7 "B.SilkS" user "B.Silkscreen")
		(1 "F.Mask" user)
		(3 "B.Mask" user)
		(17 "Dwgs.User" user "User.Drawings")
		(19 "Cmts.User" user "User.Comments")
		(21 "Eco1.User" user "User.Eco1")
		(23 "Eco2.User" user "User.Eco2")
		(25 "Edge.Cuts" user)
		(27 "Margin" user)
		(31 "F.CrtYd" user "F.Courtyard")
		(29 "B.CrtYd" user "B.Courtyard")
		(35 "F.Fab" user)
		(33 "B.Fab" user)
	)
	(footprint "antmicro-footprints:C_0402_1005Metric"
		(layer "B.Cu")
		(at 215 141.3 90)
		(descr "Capacitor SMD 0402")
		(tags "capacitor SMD 0402")
		(property "Reference" "C186"
			(at 3.64 0.08 90)
			(layer "B.SilkS")
			(effects
				(font
					(size 0.7 0.7)
					(thickness 0.15)
				)
				(justify right bottom mirror)
			)
		)
		(property "Value" "C_100n_0402"
			(at -1.022927 -2.155213 90)
			(layer "B.Fab")
			(hide yes)
			(effects
				(font
					(size 0.7 0.7)
					(thickness 0.15)
				)
				(justify right bottom mirror)
			)
		)
		(property "Datasheet" "https://www.murata.com/products/productdetail?partno=GRM155R61H104KE14%23"
			(at 0 0 90)
			(layer "F.Fab")
			(hide yes)
			(effects
				(font
					(size 1.27 1.27)
					(thickness 0.15)
				)
			)
		)
		(property "Description" "SMD Multilayer Ceramic Capacitor, 0.1 µF, 50 V, 0402 [1005 Metric], ± 10%, X5R, GRM Series"
			(at 0 0 90)
			(layer "F.Fab")
			(hide yes)
			(effects
				(font
					(size 1.27 1.27)
					(thickness 0.15)
				)
			)
		)
		(property "Author" "Antmicro"
			(at 356.3 -73.7 0)
			(layer "B.Fab")
			(hide yes)
			(effects
				(font
					(size 1 1)
					(thickness 0.15)
				)
				(justify mirror)
			)
		)
		(property "Dielectric" "X5R"
			(at 356.3 -73.7 0)
			(layer "B.Fab")
			(hide yes)
			(effects
				(font
					(size 1 1)
					(thickness 0.15)
				)
				(justify mirror)
			)
		)
		(property "License" "Apache-2.0"
			(at 356.3 -73.7 0)
			(layer "B.Fab")
			(hide yes)
			(effects
				(font
					(size 1 1)
					(thickness 0.15)
				)
				(justify mirror)
			)
		)
		(property "MPN" "GRM155R61H104KE14D"
			(at 356.3 -73.7 0)
			(layer "B.Fab")
			(hide yes)
			(effects
				(font
					(size 1 1)
					(thickness 0.15)
				)
				(justify mirror)
			)
		)
		(property "Manufacturer" "Murata"
			(at 356.3 -73.7 0)
			(layer "B.Fab")
			(hide yes)
			(effects
				(font
					(size 1 1)
					(thickness 0.15)
				)
				(justify mirror)
			)
		)
		(property "Public" ""
			(at 356.3 -73.7 0)
			(layer "B.Fab")
			(hide yes)
			(effects
				(font
					(size 1 1)
					(thickness 0.15)
				)
				(justify mirror)
			)
		)
		(property "Val" "100n"
			(at 356.3 -73.7 0)
			(layer "B.Fab")
			(hide yes)
			(effects
				(font
					(size 1 1)
					(thickness 0.15)
				)
				(justify mirror)
			)
		)
		(property "Voltage" "50V"
			(at 356.3 -73.7 0)
			(layer "B.Fab")
			(hide yes)
			(effects
				(font
					(size 1 1)
					(thickness 0.15)
				)
				(justify mirror)
			)
		)
		(sheetname "/USB/")
		(sheetfile "usb.kicad_sch")
		(attr smd)
		(fp_rect
			(start -0.925 0.47)
			(end 0.925 -0.47)
			(stroke
				(width 0.05)
				(type default)
			)
			(fill no)
			(layer "B.CrtYd")
		)
		(fp_line
			(start 0.504 -0.248)
			(end -0.494 -0.248)
			(stroke
				(width 0.15)
				(type solid)
			)
			(layer "B.Fab")
		)
		(fp_line
			(start -0.494 -0.248)
			(end -0.494 0.25)
			(stroke
				(width 0.15)
				(type solid)
			)
			(layer "B.Fab")
		)
		(fp_line
			(start 0.504 0.25)
			(end 0.504 -0.248)
			(stroke
				(width 0.15)
				(type solid)
			)
			(layer "B.Fab")
		)
		(fp_line
			(start -0.494 0.25)
			(end 0.504 0.25)
			(stroke
				(width 0.15)
				(type solid)
			)
			(layer "B.Fab")
		)
		(fp_text user "Author: Antmicro"
			(at -0.939 -3.399 270)
			(layer "B.Fab")
			(effects
				(font
					(size 0.7 0.7)
					(thickness 0.15)
				)
				(justify left bottom mirror)
			)
		)
		(fp_text user "License: Apache-2.0"
			(at -0.939 -5.799 270)
			(layer "B.Fab")
			(effects
				(font
					(size 0.7 0.7)
					(thickness 0.15)
				)
				(justify left bottom mirror)
			)
		)
		(fp_text user "${REFERENCE}"
			(at -0.939 -4.599 270)
			(layer "B.Fab")
			(effects
				(font
					(size 0.7 0.7)
					(thickness 0.15)
				)
				(justify left bottom mirror)
			)
		)
		(pad "1" smd roundrect
			(at -0.48 0 90)
			(size 0.59 0.64)
			(layers "B.Cu" "B.Mask" "B.Paste")
			(roundrect_rratio 0.25)
			(net 417 "GND")
			(pintype "passive")
		)
		(pad "2" smd roundrect
			(at 0.48 0 90)
			(size 0.59 0.64)
			(layers "B.Cu" "B.Mask" "B.Paste")
			(roundrect_rratio 0.25)
			(net 152 "/USB/VDDIO")
			(pintype "passive")
		)
	)
	(footprint "antmicro-footprints:C_0402_1005Metric"
		(layer "B.Cu")
		(at 217.361 123.254 -90)
		(descr "Capacitor SMD 0402")
		(tags "capacitor SMD 0402")
		(property "Reference" "C219"
			(at 1.816 -3.409 90)
			(layer "B.SilkS")
			(effects
				(font
					(size 0.7 0.7)
					(thickness 0.15)
				)
				(justify left bottom mirror)
			)
		)
		(property "Value" "C_10u_0402"
			(at -1.022927 -2.155213 90)
			(layer "B.Fab")
			(hide yes)
			(effects
				(font
					(size 0.7 0.7)
					(thickness 0.15)
				)
				(justify left bottom mirror)
			)
		)
		(property "Datasheet" "https://www.yageo.com/en/Chart/Download/pdf/CC0402MRX5R5BB106"
			(at 0 0 270)
			(layer "F.Fab")
			(hide yes)
			(effects
				(font
					(size 1.27 1.27)
					(thickness 0.15)
				)
			)
		)
		(property "Description" "SMD Multilayer Ceramic Capacitor, 10 µF, 6.3 V, 0402 [1005 Metric], ± 20%, X5R, CC Series"
			(at 0 0 270)
			(layer "F.Fab")
			(hide yes)
			(effects
				(font
					(size 1.27 1.27)
					(thickness 0.15)
				)
			)
		)
		(property "Author" "Antmicro"
			(at 94.107 340.615 0)
			(layer "B.Fab")
			(hide yes)
			(effects
				(font
					(size 1 1)
					(thickness 0.15)
				)
				(justify mirror)
			)
		)
		(property "Dielectric" ""
			(at 94.107 340.615 0)
			(layer "B.Fab")
			(hide yes)
			(effects
				(font
					(size 1 1)
					(thickness 0.15)
				)
				(justify mirror)
			)
		)
		(property "License" "Apache-2.0"
			(at 94.107 340.615 0)
			(layer "B.Fab")
			(hide yes)
			(effects
				(font
					(size 1 1)
					(thickness 0.15)
				)
				(justify mirror)
			)
		)
		(property "MPN" "CC0402MRX5R5BB106"
			(at 94.107 340.615 0)
			(layer "B.Fab")
			(hide yes)
			(effects
				(font
					(size 1 1)
					(thickness 0.15)
				)
				(justify mirror)
			)
		)
		(property "Manufacturer" "YAGEO"
			(at 94.107 340.615 0)
			(layer "B.Fab")
			(hide yes)
			(effects
				(font
					(size 1 1)
					(thickness 0.15)
				)
				(justify mirror)
			)
		)
		(property "Public" ""
			(at 94.107 340.615 0)
			(layer "B.Fab")
			(hide yes)
			(effects
				(font
					(size 1 1)
					(thickness 0.15)
				)
				(justify mirror)
			)
		)
		(property "Val" "10u"
			(at 94.107 340.615 0)
			(layer "B.Fab")
			(hide yes)
			(effects
				(font
					(size 1 1)
					(thickness 0.15)
				)
				(justify mirror)
			)
		)
		(property "Voltage" ""
			(at 94.107 340.615 0)
			(layer "B.Fab")
			(hide yes)
			(effects
				(font
					(size 1 1)
					(thickness 0.15)
				)
				(justify mirror)
			)
		)
		(sheetname "/Ethernet/")
		(sheetfile "ethernet.kicad_sch")
		(attr smd)
		(fp_rect
			(start -0.925 0.47)
			(end 0.925 -0.47)
			(stroke
				(width 0.05)
				(type default)
			)
			(fill no)
			(layer "B.CrtYd")
		)
		(fp_line
			(start -0.494 0.25)
			(end 0.504 0.25)
			(stroke
				(width 0.15)
				(type solid)
			)
			(layer "B.Fab")
		)
		(fp_line
			(start 0.504 0.25)
			(end 0.504 -0.248)
			(stroke
				(width 0.15)
				(type solid)
			)
			(layer "B.Fab")
		)
		(fp_line
			(start -0.494 -0.248)
			(end -0.494 0.25)
			(stroke
				(width 0.15)
				(type solid)
			)
			(layer "B.Fab")
		)
		(fp_line
			(start 0.504 -0.248)
			(end -0.494 -0.248)
			(stroke
				(width 0.15)
				(type solid)
			)
			(layer "B.Fab")
		)
		(fp_text user "Author: Antmicro"
			(at -0.939 -3.399 90)
			(layer "B.Fab")
			(effects
				(font
					(size 0.7 0.7)
					(thickness 0.15)
				)
				(justify left bottom mirror)
			)
		)
		(fp_text user "License: Apache-2.0"
			(at -0.939 -5.799 90)
			(layer "B.Fab")
			(effects
				(font
					(size 0.7 0.7)
					(thickness 0.15)
				)
				(justify left bottom mirror)
			)
		)
		(fp_text user "${REFERENCE}"
			(at -0.939 -4.599 90)
			(layer "B.Fab")
			(effects
				(font
					(size 0.7 0.7)
					(thickness 0.15)
				)
				(justify left bottom mirror)
			)
		)
		(pad "1" smd roundrect
			(at -0.48 0 270)
			(size 0.59 0.64)
			(layers "B.Cu" "B.Mask" "B.Paste")
			(roundrect_rratio 0.25)
			(net 417 "GND")
			(pintype "passive")
		)
		(pad "2" smd roundrect
			(at 0.48 0 270)
			(size 0.59 0.64)
			(layers "B.Cu" "B.Mask" "B.Paste")
			(roundrect_rratio 0.25)
			(net 47 "+1V05")
			(pintype "passive")
		)
	)
	(footprint "antmicro-footprints:TP_SMD_0.75mm"
		(layer "B.Cu")
		(at 176.45 140.9 180)
		(property "Reference" "TP4"
			(at -1.875 0.1 45)
			(layer "B.SilkS")
			(hide yes)
			(effects
				(font
					(size 0.7 0.7)
					(thickness 0.15)
				)
				(justify left bottom mirror)
			)
		)
		(property "Value" "TP_0.75mm_SMD"
			(at 0 -1.2 0)
			(layer "B.Fab")
			(hide yes)
			(effects
				(font
					(size 0.7 0.7)
					(thickness 0.15)
				)
				(justify left bottom mirror)
			)
		)
		(property "Description" "SMT test point"
			(at 0 0 0)
			(layer "B.Fab")
			(hide yes)
			(effects
				(font
					(size 1.27 1.27)
					(thickness 0.15)
				)
				(justify mirror)
			)
		)
		(property "MPN" ""
			(at 0 0 0)
			(unlocked yes)
			(layer "B.Fab")
			(hide yes)
			(effects
				(font
					(size 1 1)
					(thickness 0.15)
				)
				(justify mirror)
			)
		)
		(property "Manufacturer" ""
			(at 0 0 0)
			(unlocked yes)
			(layer "B.Fab")
			(hide yes)
			(effects
				(font
					(size 1 1)
					(thickness 0.15)
				)
				(justify mirror)
			)
		)
		(property "Author" "Antmicro"
			(at 0 0 0)
			(unlocked yes)
			(layer "B.Fab")
			(hide yes)
			(effects
				(font
					(size 1 1)
					(thickness 0.15)
				)
				(justify mirror)
			)
		)
		(property "License" "Apache-2.0"
			(at 0 0 0)
			(unlocked yes)
			(layer "B.Fab")
			(hide yes)
			(effects
				(font
					(size 1 1)
					(thickness 0.15)
				)
				(justify mirror)
			)
		)
		(property "Public" "False"
			(at 0 0 0)
			(unlocked yes)
			(layer "B.Fab")
			(hide yes)
			(effects
				(font
					(size 1 1)
					(thickness 0.15)
				)
				(justify mirror)
			)
		)
		(sheetname "/Supply/")
		(sheetfile "supply.kicad_sch")
		(attr exclude_from_pos_files exclude_from_bom)
		(fp_circle
			(center 0 0)
			(end 0.475 0)
			(stroke
				(width 0.05)
				(type default)
			)
			(fill no)
			(layer "B.CrtYd")
		)
		(fp_text user "Author: Antmicro"
			(at -0.4 -3.901 0)
			(layer "B.Fab")
			(effects
				(font
					(size 0.7 0.7)
					(thickness 0.15)
				)
				(justify left bottom mirror)
			)
		)
		(fp_text user "License: Apache-2.0"
			(at -0.4 -5.101 0)
			(layer "B.Fab")
			(effects
				(font
					(size 0.7 0.7)
					(thickness 0.15)
				)
				(justify left bottom mirror)
			)
		)
		(fp_text user "${REFERENCE}"
			(at -0.4 -2.7 0)
			(layer "B.Fab")
			(effects
				(font
					(size 0.7 0.7)
					(thickness 0.15)
				)
				(justify left bottom mirror)
			)
		)
		(pad "1" smd circle
			(at 0 0 180)
			(size 0.75 0.75)
			(layers "B.Cu" "B.Mask")
			(net 209 "/Supply/SENSE1_P")
			(pinfunction "1")
			(pintype "passive")
		)
	)
	(footprint "antmicro-footprints:C_0402_1005Metric"
		(layer "B.Cu")
		(at 195.3 126.8 180)
		(descr "Capacitor SMD 0402")
		(tags "capacitor SMD 0402")
		(property "Reference" "C9"
			(at 0.85 0.125 0)
			(layer "B.SilkS")
			(effects
				(font
					(size 0.7 0.7)
					(thickness 0.15)
				)
				(justify left bottom mirror)
			)
		)
		(property "Value" "C_4n7_0402"
			(at -1.022927 -2.155213 0)
			(layer "B.Fab")
			(hide yes)
			(effects
				(font
					(size 0.7 0.7)
					(thickness 0.15)
				)
				(justify left bottom mirror)
			)
		)
		(property "Datasheet" "https://product.tdk.com/en/search/capacitor/ceramic/mlcc/info?part_no=CGA2B3X7S2A472K050BB"
			(at 0 0 180)
			(layer "F.Fab")
			(hide yes)
			(effects
				(font
					(size 1.27 1.27)
					(thickness 0.15)
				)
			)
		)
		(property "Description" "SMD Multilayer Ceramic Capacitor, 4700 pF, 100 V, 0402 [1005 Metric], ± 10%, X7S, CGA"
			(at 0 0 180)
			(layer "F.Fab")
			(hide yes)
			(effects
				(font
					(size 1.27 1.27)
					(thickness 0.15)
				)
			)
		)
		(property "Author" "Antmicro"
			(at 390.6 253.6 0)
			(layer "B.Fab")
			(hide yes)
			(effects
				(font
					(size 1 1)
					(thickness 0.15)
				)
				(justify mirror)
			)
		)
		(property "Dielectric" "X7R"
			(at 390.6 253.6 0)
			(layer "B.Fab")
			(hide yes)
			(effects
				(font
					(size 1 1)
					(thickness 0.15)
				)
				(justify mirror)
			)
		)
		(property "License" "Apache-2.0"
			(at 390.6 253.6 0)
			(layer "B.Fab")
			(hide yes)
			(effects
				(font
					(size 1 1)
					(thickness 0.15)
				)
				(justify mirror)
			)
		)
		(property "MPN" "CGA2B3X7S2A472K050BB"
			(at 390.6 253.6 0)
			(layer "B.Fab")
			(hide yes)
			(effects
				(font
					(size 1 1)
					(thickness 0.15)
				)
				(justify mirror)
			)
		)
		(property "Manufacturer" "TDK"
			(at 390.6 253.6 0)
			(layer "B.Fab")
			(hide yes)
			(effects
				(font
					(size 1 1)
					(thickness 0.15)
				)
				(justify mirror)
			)
		)
		(property "Public" ""
			(at 390.6 253.6 0)
			(layer "B.Fab")
			(hide yes)
			(effects
				(font
					(size 1 1)
					(thickness 0.15)
				)
				(justify mirror)
			)
		)
		(property "Val" "4n7"
			(at 390.6 253.6 0)
			(layer "B.Fab")
			(hide yes)
			(effects
				(font
					(size 1 1)
					(thickness 0.15)
				)
				(justify mirror)
			)
		)
		(property "Voltage" "25V"
			(at 390.6 253.6 0)
			(layer "B.Fab")
			(hide yes)
			(effects
				(font
					(size 1 1)
					(thickness 0.15)
				)
				(justify mirror)
			)
		)
		(sheetname "/FPGA Supply/")
		(sheetfile "fpga-supply.kicad_sch")
		(attr smd)
		(fp_rect
			(start -0.925 0.47)
			(end 0.925 -0.47)
			(stroke
				(width 0.05)
				(type default)
			)
			(fill no)
			(layer "B.CrtYd")
		)
		(fp_line
			(start 0.504 0.25)
			(end 0.504 -0.248)
			(stroke
				(width 0.15)
				(type solid)
			)
			(layer "B.Fab")
		)
		(fp_line
			(start 0.504 -0.248)
			(end -0.494 -0.248)
			(stroke
				(width 0.15)
				(type solid)
			)
			(layer "B.Fab")
		)
		(fp_line
			(start -0.494 0.25)
			(end 0.504 0.25)
			(stroke
				(width 0.15)
				(type solid)
			)
			(layer "B.Fab")
		)
		(fp_line
			(start -0.494 -0.248)
			(end -0.494 0.25)
			(stroke
				(width 0.15)
				(type solid)
			)
			(layer "B.Fab")
		)
		(fp_text user "${REFERENCE}"
			(at -0.939 -4.599 0)
			(layer "B.Fab")
			(effects
				(font
					(size 0.7 0.7)
					(thickness 0.15)
				)
				(justify left bottom mirror)
			)
		)
		(fp_text user "Author: Antmicro"
			(at -0.939 -3.399 0)
			(layer "B.Fab")
			(effects
				(font
					(size 0.7 0.7)
					(thickness 0.15)
				)
				(justify left bottom mirror)
			)
		)
		(fp_text user "License: Apache-2.0"
			(at -0.939 -5.799 0)
			(layer "B.Fab")
			(effects
				(font
					(size 0.7 0.7)
					(thickness 0.15)
				)
				(justify left bottom mirror)
			)
		)
		(pad "1" smd roundrect
			(at -0.48 0 180)
			(size 0.59 0.64)
			(layers "B.Cu" "B.Mask" "B.Paste")
			(roundrect_rratio 0.25)
			(net 417 "GND")
			(pintype "passive")
		)
		(pad "2" smd roundrect
			(at 0.48 0 180)
			(size 0.59 0.64)
			(layers "B.Cu" "B.Mask" "B.Paste")
			(roundrect_rratio 0.25)
			(net 2 "+1V1")
			(pintype "passive")
		)
	)
	(footprint "antmicro-footprints:R_0402_1005Metric"
		(layer "B.Cu")
		(at 208.25 134.35 180)
		(descr "Resistor SMD 0402")
		(tags "resistor SMD 0402")
		(property "Reference" "R39"
			(at 0.85 -0.4 0)
			(layer "B.SilkS")
			(effects
				(font
					(size 0.7 0.7)
					(thickness 0.15)
				)
				(justify left bottom mirror)
			)
		)
		(property "Value" "R_4k7_0402"
			(at -1.011843 -1.772047 0)
			(layer "B.Fab")
			(hide yes)
			(effects
				(font
					(size 0.7 0.7)
					(thickness 0.15)
				)
				(justify left bottom mirror)
			)
		)
		(property "Datasheet" "https://www.bourns.com/docs/product-datasheets/cr.pdf"
			(at 0 0 180)
			(layer "F.Fab")
			(hide yes)
			(effects
				(font
					(size 1.27 1.27)
					(thickness 0.15)
				)
			)
		)
		(property "Description" "SMD Chip Resistor, 4.7 kohm, ± 1%, 62.5 mW, 0402 [1005 Metric], Thick Film, General Purpose"
			(at 0 0 180)
			(layer "F.Fab")
			(hide yes)
			(effects
				(font
					(size 1.27 1.27)
					(thickness 0.15)
				)
			)
		)
		(property "Author" "Antmicro"
			(at 416.5 268.7 0)
			(layer "B.Fab")
			(hide yes)
			(effects
				(font
					(size 1 1)
					(thickness 0.15)
				)
				(justify mirror)
			)
		)
		(property "DNP" "DNP"
			(at 416.5 268.7 0)
			(layer "B.Fab")
			(hide yes)
			(effects
				(font
					(size 1 1)
					(thickness 0.15)
				)
				(justify mirror)
			)
		)
		(property "License" "Apache-2.0"
			(at 416.5 268.7 0)
			(layer "B.Fab")
			(hide yes)
			(effects
				(font
					(size 1 1)
					(thickness 0.15)
				)
				(justify mirror)
			)
		)
		(property "MPN" "CR0402-FX-4701GLF"
			(at 416.5 268.7 0)
			(layer "B.Fab")
			(hide yes)
			(effects
				(font
					(size 1 1)
					(thickness 0.15)
				)
				(justify mirror)
			)
		)
		(property "Manufacturer" "Bourns"
			(at 416.5 268.7 0)
			(layer "B.Fab")
			(hide yes)
			(effects
				(font
					(size 1 1)
					(thickness 0.15)
				)
				(justify mirror)
			)
		)
		(property "Public" ""
			(at 416.5 268.7 0)
			(layer "B.Fab")
			(hide yes)
			(effects
				(font
					(size 1 1)
					(thickness 0.15)
				)
				(justify mirror)
			)
		)
		(property "Tolerance" "1%"
			(at 416.5 268.7 0)
			(layer "B.Fab")
			(hide yes)
			(effects
				(font
					(size 1 1)
					(thickness 0.15)
				)
				(justify mirror)
			)
		)
		(property "Val" "4k7"
			(at 416.5 268.7 0)
			(layer "B.Fab")
			(hide yes)
			(effects
				(font
					(size 1 1)
					(thickness 0.15)
				)
				(justify mirror)
			)
		)
		(sheetname "/FPGA Config/")
		(sheetfile "fpga-config.kicad_sch")
		(attr smd dnp)
		(fp_rect
			(start -0.925 0.47)
			(end 0.925 -0.47)
			(stroke
				(width 0.05)
				(type default)
			)
			(fill no)
			(layer "B.CrtYd")
		)
		(fp_rect
			(start -0.5 0.25)
			(end 0.5 -0.25)
			(stroke
				(width 0.15)
				(type solid)
			)
			(fill no)
			(layer "B.Fab")
		)
		(fp_text user "${REFERENCE}"
			(at -0.95 -3.168 0)
			(layer "B.Fab")
			(effects
				(font
					(size 0.7 0.7)
					(thickness 0.15)
				)
				(justify left bottom mirror)
			)
		)
		(fp_text user "License: Apache-2.0"
			(at -0.95 -5.169 0)
			(layer "B.Fab")
			(effects
				(font
					(size 0.7 0.7)
					(thickness 0.15)
				)
				(justify left bottom mirror)
			)
		)
		(fp_text user "Author: Antmicro"
			(at -0.95 -4.169 0)
			(layer "B.Fab")
			(effects
				(font
					(size 0.7 0.7)
					(thickness 0.15)
				)
				(justify left bottom mirror)
			)
		)
		(pad "1" smd roundrect
			(at -0.48 0 180)
			(size 0.59 0.64)
			(layers "B.Cu" "B.Mask" "B.Paste")
			(roundrect_rratio 0.25)
			(net 50 "+3V3")
			(pintype "passive")
		)
		(pad "2" smd roundrect
			(at 0.48 0 180)
			(size 0.59 0.64)
			(layers "B.Cu" "B.Mask" "B.Paste")
			(roundrect_rratio 0.25)
			(net 254 "Net-(U1D-FF_EXIT_N)")
			(pintype "passive")
		)
	)
)
